(kicad_pcb
	(version 20260206)
	(generator "pcbnew")
	(generator_version "10.0")
	(general
		(thickness 1.6)
		(legacy_teardrops no)
	)
	(paper "A4")
	(title_block
		(title "Bryce Canyon_R.DPB_16317-1_OCP.brd")
		(comment 1 "Bryce Canyon / footprints 140-147 of 2099")
	)
	(layers
		(0 "F.Cu" signal "TOP")
		(4 "In1.Cu" signal "L2GND")
		(6 "In2.Cu" signal "L3")
		(8 "In3.Cu" signal "L4VCC")
		(10 "In4.Cu" signal "L5VCC")
		(12 "In5.Cu" signal "L6")
		(14 "In6.Cu" signal "L7GND")
		(2 "B.Cu" signal "BOTTOM")
		(9 "F.Adhes" user "F.Adhesive")
		(11 "B.Adhes" user "B.Adhesive")
		(13 "F.Paste" user "Package Geometry/Pastemask Top")
		(15 "B.Paste" user "Package Geometry/Pastemask Bottom")
		(5 "F.SilkS" user "Ref Des/Silkscreen Top")
		(7 "B.SilkS" user "Ref Des/Silkscreen Bottom")
		(1 "F.Mask" user "Board Geometry/Soldermask Top")
		(3 "B.Mask" user "Board Geometry/Soldermask Bottom")
		(17 "Dwgs.User" user "User.Drawings")
		(19 "Cmts.User" user "User.Comments")
		(21 "Eco1.User" user "User.Eco1")
		(23 "Eco2.User" user "User.Eco2")
		(25 "Edge.Cuts" user "Board Geometry/Outline")
		(27 "Margin" user)
		(31 "F.CrtYd" user "Package Geometry/Place Bound Top")
		(29 "B.CrtYd" user "Package Geometry/Place Bound Bottom")
		(35 "F.Fab" user "Ref Des/Assembly Top")
		(33 "B.Fab" user "Ref Des/Assembly Bottom")
	)
	(footprint ""
		(layer "F.Cu")
		(at 37.0332 -12.319 -90)
		(property "Reference" "R127"
			(at 0 0 270)
			(layer "F.SilkS")
			(hide yes)
			(effects
				(font
					(size 1.27 1.27)
				)
			)
		)
		(property "Value" "0R2J-2-GP"
			(at 0.064008 -3.993896 270)
			(unlocked yes)
			(layer "F.Fab")
			(hide yes)
			(effects
				(font
					(size 1.016 1.016)
					(thickness 0.1524)
				)
			)
		)
		(property "Device Type" "R402H16"
			(at 0.064008 -5.517896 270)
			(unlocked yes)
			(layer "F.Fab")
			(hide yes)
			(effects
				(font
					(size 1.016 1.016)
					(thickness 0.1524)
				)
			)
		)
		(duplicate_pad_numbers_are_jumpers no)
		(fp_line
			(start -0.508 -0.9398)
			(end -0.508 0.9398)
			(stroke
				(width 0.1524)
				(type default)
			)
			(layer "F.SilkS")
		)
		(fp_line
			(start 0.508 -0.9398)
			(end -0.508 -0.9398)
			(stroke
				(width 0.1524)
				(type default)
			)
			(layer "F.SilkS")
		)
		(fp_rect
			(start -0.508 0.9398)
			(end 0.508 -0.9398)
			(stroke
				(width 0)
				(type default)
			)
			(fill no)
			(layer "F.CrtYd")
		)
		(fp_rect
			(start -0.508 0.9398)
			(end 0.508 -0.9398)
			(stroke
				(width 0)
				(type default)
			)
			(fill no)
			(layer "F.Fab")
		)
		(pad "1" smd custom
			(at 0 -0.4445 270)
			(size 0.1397 0.1397)
			(layers "F.Cu" "F.Mask" "F.Paste")
			(net "I2C_DPB_A_SCL_BUF")
			(options
				(clearance outline)
				(anchor circle)
			)
			(primitives
				(gr_poly
					(pts
						(arc
							(start -0.1778 -0.2794)
							(mid -0.249642 -0.249642)
							(end -0.2794 -0.1778)
						)
						(arc
							(start -0.2794 0.1778)
							(mid -0.249642 0.249642)
							(end -0.1778 0.2794)
						)
						(arc
							(start 0.1778 0.2794)
							(mid 0.249642 0.249642)
							(end 0.2794 0.1778)
						)
						(arc
							(start 0.2794 -0.1778)
							(mid 0.249642 -0.249642)
							(end 0.1778 -0.2794)
						)
					)
					(width 0)
					(fill yes)
				)
			)
		)
		(pad "2" smd custom
			(at 0 0.4445 270)
			(size 0.1397 0.1397)
			(layers "F.Cu" "F.Mask" "F.Paste")
			(net "TEMP1_SCL")
			(options
				(clearance outline)
				(anchor circle)
			)
			(primitives
				(gr_poly
					(pts
						(arc
							(start -0.1778 -0.2794)
							(mid -0.249642 -0.249642)
							(end -0.2794 -0.1778)
						)
						(arc
							(start -0.2794 0.1778)
							(mid -0.249642 0.249642)
							(end -0.1778 0.2794)
						)
						(arc
							(start 0.1778 0.2794)
							(mid 0.249642 0.249642)
							(end 0.2794 0.1778)
						)
						(arc
							(start 0.2794 -0.1778)
							(mid 0.249642 -0.249642)
							(end 0.1778 -0.2794)
						)
					)
					(width 0)
					(fill yes)
				)
			)
		)
	)
	(footprint ""
		(layer "F.Cu")
		(at 321.7164 -146.6342)
		(property "Reference" "C269"
			(at 0 0 0)
			(layer "F.SilkS")
			(hide yes)
			(effects
				(font
					(size 1.27 1.27)
				)
			)
		)
		(property "Value" "SCD01U50V2KX-1GP"
			(at 1.1811 -2.7051 0)
			(unlocked yes)
			(layer "F.Fab")
			(hide yes)
			(effects
				(font
					(size 1.016 1.016)
					(thickness 0.1524)
				)
			)
		)
		(property "Device Type" "C402H22"
			(at 1.1811 -4.2291 0)
			(unlocked yes)
			(layer "F.Fab")
			(hide yes)
			(effects
				(font
					(size 1.016 1.016)
					(thickness 0.1524)
				)
			)
		)
		(duplicate_pad_numbers_are_jumpers no)
		(fp_rect
			(start -0.4318 0.9525)
			(end 0.4318 -0.9525)
			(stroke
				(width 0)
				(type default)
			)
			(fill no)
			(layer "F.CrtYd")
		)
		(fp_rect
			(start -0.4318 0.9525)
			(end 0.4318 -0.9525)
			(stroke
				(width 0)
				(type default)
			)
			(fill no)
			(layer "F.Fab")
		)
		(pad "1" smd custom
			(at 0 -0.4445)
			(size 0.1524 0.1524)
			(layers "F.Cu" "F.Mask" "F.Paste")
			(net "HDD_PRSNT_18")
			(options
				(clearance outline)
				(anchor circle)
			)
			(primitives
				(gr_poly
					(pts
						(arc
							(start 0.3048 -0.2032)
							(mid 0.275042 -0.275042)
							(end 0.2032 -0.3048)
						)
						(arc
							(start -0.2032 -0.3048)
							(mid -0.275042 -0.275042)
							(end -0.3048 -0.2032)
						)
						(arc
							(start -0.3048 0.2032)
							(mid -0.275042 0.275042)
							(end -0.2032 0.3048)
						)
						(arc
							(start 0.2032 0.3048)
							(mid 0.275042 0.275042)
							(end 0.3048 0.2032)
						)
					)
					(width 0)
					(fill yes)
				)
			)
		)
		(pad "2" smd custom
			(at 0 0.4445)
			(size 0.1524 0.1524)
			(layers "F.Cu" "F.Mask" "F.Paste")
			(net "GND")
			(options
				(clearance outline)
				(anchor circle)
			)
			(primitives
				(gr_poly
					(pts
						(arc
							(start 0.3048 -0.2032)
							(mid 0.275042 -0.275042)
							(end 0.2032 -0.3048)
						)
						(arc
							(start -0.2032 -0.3048)
							(mid -0.275042 -0.275042)
							(end -0.3048 -0.2032)
						)
						(arc
							(start -0.3048 0.2032)
							(mid -0.275042 0.275042)
							(end -0.2032 0.3048)
						)
						(arc
							(start 0.2032 0.3048)
							(mid 0.275042 0.275042)
							(end 0.3048 0.2032)
						)
					)
					(width 0)
					(fill yes)
				)
			)
		)
	)
	(footprint ""
		(layer "F.Cu")
		(at 382.315974 -154.70505)
		(property "Reference" "TP121"
			(at 0 0 0)
			(layer "F.SilkS")
			(hide yes)
			(effects
				(font
					(size 1.27 1.27)
				)
			)
		)
		(property "Value" "*"
			(at -0.0508 -1.6764 0)
			(unlocked yes)
			(layer "F.Fab")
			(hide yes)
			(effects
				(font
					(size 1.016 1.016)
					(thickness 0.1524)
				)
			)
		)
		(property "Device Type" "TPAD32"
			(at -0.0508 -3.2004 0)
			(unlocked yes)
			(layer "F.Fab")
			(hide yes)
			(effects
				(font
					(size 1.016 1.016)
					(thickness 0.1524)
				)
			)
		)
		(duplicate_pad_numbers_are_jumpers no)
		(fp_poly
			(pts
				(arc
					(start 0.4064 0)
					(mid -0.4064 0)
					(end 0.4064 0)
				)
			)
			(stroke
				(width 0)
				(type default)
			)
			(fill no)
			(layer "F.CrtYd")
		)
		(fp_poly
			(pts
				(arc
					(start 0.7112 0)
					(mid -0.7112 0)
					(end 0.7112 0)
				)
			)
			(stroke
				(width 0)
				(type default)
			)
			(fill no)
			(layer "F.Fab")
		)
		(pad "1" smd circle
			(at 0 0)
			(size 0.8128 0.8128)
			(layers "F.Cu" "F.Mask" "F.Paste")
			(net "ACT_HDD_20")
		)
	)
	(footprint ""
		(layer "F.Cu")
		(at 417.966652 -132.437124)
		(property "Reference" "VIA44"
			(at 0 0 0)
			(layer "F.SilkS")
			(hide yes)
			(effects
				(font
					(size 1.27 1.27)
				)
			)
		)
		(property "Value" "100OHM-8L-2D36MM-L16-GP"
			(at -3.4036 -0.4572 0)
			(unlocked yes)
			(layer "F.Fab")
			(hide yes)
			(effects
				(font
					(size 1.016 1.016)
					(thickness 0.1524)
				)
			)
		)
		(property "Device Type" "VIA-PCIE-4P-427097"
			(at -3.4036 -1.9812 0)
			(unlocked yes)
			(layer "F.Fab")
			(hide yes)
			(effects
				(font
					(size 1.016 1.016)
					(thickness 0.1524)
				)
			)
		)
		(duplicate_pad_numbers_are_jumpers no)
		(fp_rect
			(start -2.1336 0.4826)
			(end 2.1336 -0.4826)
			(stroke
				(width 0)
				(type default)
			)
			(fill no)
			(layer "F.CrtYd")
		)
		(fp_rect
			(start -2.1336 0.4826)
			(end 2.1336 -0.4826)
			(stroke
				(width 0)
				(type default)
			)
			(fill no)
			(layer "F.Fab")
		)
		(pad "1" thru_hole circle
			(at -1.651 0)
			(size 0.508 0.508)
			(drill 0.254)
			(layers "*.Cu" "*.Mask")
			(remove_unused_layers no)
			(net "GND")
			(clearance 0.2286)
			(thermal_gap 0.2286)
		)
		(pad "2" thru_hole circle
			(at -0.635 0)
			(size 0.508 0.508)
			(drill 0.254)
			(layers "*.Cu" "*.Mask")
			(remove_unused_layers no)
			(net "PHY_DRV_B_TO_SCC_B_21_DP")
			(clearance 0.2286)
			(thermal_gap 0.2286)
		)
		(pad "3" thru_hole circle
			(at 0.635 0)
			(size 0.508 0.508)
			(drill 0.254)
			(layers "*.Cu" "*.Mask")
			(remove_unused_layers no)
			(net "PHY_DRV_B_TO_SCC_B_21_DN")
			(clearance 0.2286)
			(thermal_gap 0.2286)
		)
		(pad "4" thru_hole circle
			(at 1.651 0)
			(size 0.508 0.508)
			(drill 0.254)
			(layers "*.Cu" "*.Mask")
			(remove_unused_layers no)
			(net "GND")
			(clearance 0.2286)
			(thermal_gap 0.2286)
		)
	)
	(footprint ""
		(layer "F.Cu")
		(at 78.11135 -102.427786 -90)
		(property "Reference" "R372"
			(at 0 0 270)
			(layer "F.SilkS")
			(hide yes)
			(effects
				(font
					(size 1.27 1.27)
				)
			)
		)
		(property "Value" "4K7R2F-GP"
			(at 0.064008 -3.993896 270)
			(unlocked yes)
			(layer "F.Fab")
			(hide yes)
			(effects
				(font
					(size 1.016 1.016)
					(thickness 0.1524)
				)
			)
		)
		(property "Device Type" "R402H16"
			(at 0.064008 -5.517896 270)
			(unlocked yes)
			(layer "F.Fab")
			(hide yes)
			(effects
				(font
					(size 1.016 1.016)
					(thickness 0.1524)
				)
			)
		)
		(duplicate_pad_numbers_are_jumpers no)
		(fp_line
			(start -0.508 -0.9398)
			(end -0.508 0.9398)
			(stroke
				(width 0.1524)
				(type default)
			)
			(layer "F.SilkS")
		)
		(fp_line
			(start 0.508 -0.9398)
			(end -0.508 -0.9398)
			(stroke
				(width 0.1524)
				(type default)
			)
			(layer "F.SilkS")
		)
		(fp_rect
			(start -0.508 0.9398)
			(end 0.508 -0.9398)
			(stroke
				(width 0)
				(type default)
			)
			(fill no)
			(layer "F.CrtYd")
		)
		(fp_rect
			(start -0.508 0.9398)
			(end 0.508 -0.9398)
			(stroke
				(width 0)
				(type default)
			)
			(fill no)
			(layer "F.Fab")
		)
		(pad "1" smd custom
			(at 0 -0.4445 270)
			(size 0.1397 0.1397)
			(layers "F.Cu" "F.Mask" "F.Paste")
			(net "DRIVE_B_14_FLT_LED")
			(options
				(clearance outline)
				(anchor circle)
			)
			(primitives
				(gr_poly
					(pts
						(arc
							(start -0.1778 -0.2794)
							(mid -0.249642 -0.249642)
							(end -0.2794 -0.1778)
						)
						(arc
							(start -0.2794 0.1778)
							(mid -0.249642 0.249642)
							(end -0.1778 0.2794)
						)
						(arc
							(start 0.1778 0.2794)
							(mid 0.249642 0.249642)
							(end 0.2794 0.1778)
						)
						(arc
							(start 0.2794 -0.1778)
							(mid 0.249642 -0.249642)
							(end 0.1778 -0.2794)
						)
					)
					(width 0)
					(fill yes)
				)
			)
		)
		(pad "2" smd custom
			(at 0 0.4445 270)
			(size 0.1397 0.1397)
			(layers "F.Cu" "F.Mask" "F.Paste")
			(net "GND")
			(options
				(clearance outline)
				(anchor circle)
			)
			(primitives
				(gr_poly
					(pts
						(arc
							(start -0.1778 -0.2794)
							(mid -0.249642 -0.249642)
							(end -0.2794 -0.1778)
						)
						(arc
							(start -0.2794 0.1778)
							(mid -0.249642 0.249642)
							(end -0.1778 0.2794)
						)
						(arc
							(start 0.1778 0.2794)
							(mid 0.249642 0.249642)
							(end 0.2794 0.1778)
						)
						(arc
							(start 0.2794 -0.1778)
							(mid 0.249642 -0.249642)
							(end 0.1778 -0.2794)
						)
					)
					(width 0)
					(fill yes)
				)
			)
		)
	)
	(footprint ""
		(layer "F.Cu")
		(at 366.395 -23.876 -90)
		(property "Reference" "Q159"
			(at 0 0 270)
			(layer "F.SilkS")
			(hide yes)
			(effects
				(font
					(size 1.27 1.27)
				)
			)
		)
		(property "Value" "AO4406AL-GP"
			(at -3.707384 -1.5367 270)
			(unlocked yes)
			(layer "F.Fab")
			(hide yes)
			(effects
				(font
					(size 1.016 1.016)
					(thickness 0.1524)
				)
			)
		)
		(property "Device Type" "SOIC8H69"
			(at -3.707384 -3.0607 270)
			(unlocked yes)
			(layer "F.Fab")
			(hide yes)
			(effects
				(font
					(size 1.016 1.016)
					(thickness 0.1524)
				)
			)
		)
		(duplicate_pad_numbers_are_jumpers no)
		(fp_line
			(start -2.6289 3.4417)
			(end -2.6289 1.4732)
			(stroke
				(width 0.381)
				(type default)
			)
			(layer "F.SilkS")
		)
		(fp_line
			(start -2.7432 1.4224)
			(end -2.6416 1.4224)
			(stroke
				(width 0.1524)
				(type default)
			)
			(layer "F.SilkS")
		)
		(fp_line
			(start -2.7432 1.4224)
			(end 2.1336 1.4224)
			(stroke
				(width 0.1524)
				(type default)
			)
			(layer "F.SilkS")
		)
		(fp_line
			(start 2.1336 1.4224)
			(end 2.1336 -1.4224)
			(stroke
				(width 0.1524)
				(type default)
			)
			(layer "F.SilkS")
		)
		(fp_line
			(start -2.1844 -0.0508)
			(end -2.7178 0.508)
			(stroke
				(width 0.1524)
				(type default)
			)
			(layer "F.SilkS")
		)
		(fp_line
			(start -2.7178 -0.508)
			(end -2.1844 -0.0508)
			(stroke
				(width 0.1524)
				(type default)
			)
			(layer "F.SilkS")
		)
		(fp_line
			(start -2.7432 -1.4224)
			(end -2.7432 1.4224)
			(stroke
				(width 0.1524)
				(type default)
			)
			(layer "F.SilkS")
		)
		(fp_line
			(start 2.1336 -1.4224)
			(end -2.7432 -1.4224)
			(stroke
				(width 0.1524)
				(type default)
			)
			(layer "F.SilkS")
		)
		(fp_poly
			(pts
				(xy -2.2098 -1.4224) (xy -2.2098 1.4224) (xy 2.2098 1.4224) (xy 2.2098 -1.4224)
			)
			(stroke
				(width 0)
				(type default)
			)
			(fill yes)
			(layer "F.SilkS")
		)
		(fp_rect
			(start -2.450084 2.999994)
			(end 2.450084 -2.999994)
			(stroke
				(width 0)
				(type default)
			)
			(fill no)
			(layer "F.CrtYd")
		)
		(fp_poly
			(pts
				(xy -2.8194 3.6322) (xy -2.8194 -3.6322) (xy 2.8194 -3.6322) (xy 2.8194 1.18364) (xy 2.450084 1.18364)
				(xy 2.450084 -2.999994) (xy -2.450084 -2.999994) (xy -2.450084 2.999994) (xy 2.450084 2.999994)
				(xy 2.450084 1.18618) (xy 2.8194 1.18618) (xy 2.8194 3.6322)
			)
			(stroke
				(width 0)
				(type default)
			)
			(fill no)
			(layer "F.CrtYd")
		)
		(fp_rect
			(start -2.8194 3.6322)
			(end 2.8194 -3.6322)
			(stroke
				(width 0)
				(type default)
			)
			(fill no)
			(layer "F.Fab")
		)
		(pad "1" smd rect
			(at -1.905 2.54 270)
			(size 0.635 1.651)
			(layers "F.Cu" "F.Mask" "F.Paste")
			(net "P5V_HDD31")
		)
		(pad "2" smd rect
			(at -0.635 2.54 270)
			(size 0.635 1.651)
			(layers "F.Cu" "F.Mask" "F.Paste")
			(net "P5V_HDD31")
		)
		(pad "3" smd rect
			(at 0.635 2.54 270)
			(size 0.635 1.651)
			(layers "F.Cu" "F.Mask" "F.Paste")
			(net "P5V_HDD31")
		)
		(pad "4" smd rect
			(at 1.905 2.54 270)
			(size 0.635 1.651)
			(layers "F.Cu" "F.Mask" "F.Paste")
			(net "SW_HDD_P31")
		)
		(pad "5" smd rect
			(at 1.905 -2.54 270)
			(size 0.635 1.651)
			(layers "F.Cu" "F.Mask" "F.Paste")
			(net "P5V_B_4")
		)
		(pad "6" smd rect
			(at 0.635 -2.54 270)
			(size 0.635 1.651)
			(layers "F.Cu" "F.Mask" "F.Paste")
			(net "P5V_B_4")
		)
		(pad "7" smd rect
			(at -0.635 -2.54 270)
			(size 0.635 1.651)
			(layers "F.Cu" "F.Mask" "F.Paste")
			(net "P5V_B_4")
		)
		(pad "8" smd rect
			(at -1.905 -2.54 270)
			(size 0.635 1.651)
			(layers "F.Cu" "F.Mask" "F.Paste")
			(net "P5V_B_4")
		)
	)
	(footprint ""
		(layer "F.Cu")
		(at 407.093928 -102.413562 -90)
		(property "Reference" "R480"
			(at 0 0 270)
			(layer "F.SilkS")
			(hide yes)
			(effects
				(font
					(size 1.27 1.27)
				)
			)
		)
		(property "Value" "4K7R2F-GP"
			(at 0.064008 -3.993896 270)
			(unlocked yes)
			(layer "F.Fab")
			(hide yes)
			(effects
				(font
					(size 1.016 1.016)
					(thickness 0.1524)
				)
			)
		)
		(property "Device Type" "R402H16"
			(at 0.064008 -5.517896 270)
			(unlocked yes)
			(layer "F.Fab")
			(hide yes)
			(effects
				(font
					(size 1.016 1.016)
					(thickness 0.1524)
				)
			)
		)
		(duplicate_pad_numbers_are_jumpers no)
		(fp_line
			(start -0.508 -0.9398)
			(end -0.508 0.9398)
			(stroke
				(width 0.1524)
				(type default)
			)
			(layer "F.SilkS")
		)
		(fp_line
			(start 0.508 -0.9398)
			(end -0.508 -0.9398)
			(stroke
				(width 0.1524)
				(type default)
			)
			(layer "F.SilkS")
		)
		(fp_rect
			(start -0.508 0.9398)
			(end 0.508 -0.9398)
			(stroke
				(width 0)
				(type default)
			)
			(fill no)
			(layer "F.CrtYd")
		)
		(fp_rect
			(start -0.508 0.9398)
			(end 0.508 -0.9398)
			(stroke
				(width 0)
				(type default)
			)
			(fill no)
			(layer "F.Fab")
		)
		(pad "1" smd custom
			(at 0 -0.4445 270)
			(size 0.1397 0.1397)
			(layers "F.Cu" "F.Mask" "F.Paste")
			(net "DRIVE_B_21_FLT_LED")
			(options
				(clearance outline)
				(anchor circle)
			)
			(primitives
				(gr_poly
					(pts
						(arc
							(start -0.1778 -0.2794)
							(mid -0.249642 -0.249642)
							(end -0.2794 -0.1778)
						)
						(arc
							(start -0.2794 0.1778)
							(mid -0.249642 0.249642)
							(end -0.1778 0.2794)
						)
						(arc
							(start 0.1778 0.2794)
							(mid 0.249642 0.249642)
							(end 0.2794 0.1778)
						)
						(arc
							(start 0.2794 -0.1778)
							(mid 0.249642 -0.249642)
							(end 0.1778 -0.2794)
						)
					)
					(width 0)
					(fill yes)
				)
			)
		)
		(pad "2" smd custom
			(at 0 0.4445 270)
			(size 0.1397 0.1397)
			(layers "F.Cu" "F.Mask" "F.Paste")
			(net "GND")
			(options
				(clearance outline)
				(anchor circle)
			)
			(primitives
				(gr_poly
					(pts
						(arc
							(start -0.1778 -0.2794)
							(mid -0.249642 -0.249642)
							(end -0.2794 -0.1778)
						)
						(arc
							(start -0.2794 0.1778)
							(mid -0.249642 0.249642)
							(end -0.1778 0.2794)
						)
						(arc
							(start 0.1778 0.2794)
							(mid 0.249642 0.249642)
							(end 0.2794 0.1778)
						)
						(arc
							(start 0.2794 -0.1778)
							(mid 0.249642 -0.249642)
							(end 0.1778 -0.2794)
						)
					)
					(width 0)
					(fill yes)
				)
			)
		)
	)
	(footprint ""
		(layer "F.Cu")
		(at 97.863914 -269.705074)
		(property "Reference" "TP31"
			(at 0 0 0)
			(layer "F.SilkS")
			(hide yes)
			(effects
				(font
					(size 1.27 1.27)
				)
			)
		)
		(property "Value" "*"
			(at -0.0508 -1.6764 0)
			(unlocked yes)
			(layer "F.Fab")
			(hide yes)
			(effects
				(font
					(size 1.016 1.016)
					(thickness 0.1524)
				)
			)
		)
		(property "Device Type" "TPAD32"
			(at -0.0508 -3.2004 0)
			(unlocked yes)
			(layer "F.Fab")
			(hide yes)
			(effects
				(font
					(size 1.016 1.016)
					(thickness 0.1524)
				)
			)
		)
		(duplicate_pad_numbers_are_jumpers no)
		(fp_poly
			(pts
				(arc
					(start 0.4064 0)
					(mid -0.4064 0)
					(end 0.4064 0)
				)
			)
			(stroke
				(width 0)
				(type default)
			)
			(fill no)
			(layer "F.CrtYd")
		)
		(fp_poly
			(pts
				(arc
					(start 0.7112 0)
					(mid -0.7112 0)
					(end 0.7112 0)
				)
			)
			(stroke
				(width 0)
				(type default)
			)
			(fill no)
			(layer "F.Fab")
		)
		(pad "1" smd circle
			(at 0 0)
			(size 0.8128 0.8128)
			(layers "F.Cu" "F.Mask" "F.Paste")
			(net "ACT_HDD_2")
		)
	)
)
